FILE_TYPE = CONNECTIVITY;
{Allegro Design Entry HDL 17.4-2019 S026 (4007227) 1/17/2022}
"PAGE_NUMBER" = 186;
0"NC";
1"GND\g";
2"GND\g";
3"GND\g";
4"GND\g";
5"GND\g";
6"GND\g";
7"GND\g";
8"P5V_AUX\g";
9"GND\g";
10"P3V3_AUX\g";
11"GND\g";
12"GND\g";
13"GND\g";
14"PVDDCR_CPU0_P1_VCCS";
15"PVDDCR_CPU0_P1_VCC2";
16"SW_P12V_AUX_PVDDCR_CPU0_P1_FLT\g";
17"GND\g";
18"SW_PVDDCR_CPU0_P1_BOOT2";
19"SW_PVDDCR_CPU0_P1_PH2";
20"PVDDCR_CPU0_P1_VOS1";
21"SW_PVDDCR_CPU0_P1_SW1";
22"SW_PVDDCR_CPU0_P1_PH1";
23"SW_P12V_AUX_PVDDCR_CPU0_P1_FLT\g";
24"SW_PVDDCR_CPU0_P1_BOOT1";
25"PVDDCR_CPU0_P1_VCC1";
26"SW_PVDDCR_CPU0_P1_BOOT2_RC";
27"SW_PVDDCR_CPU0_P1_BOOT1_RC";
28"PVDDCR_CPU0_P1_PVCC\g";
29"GND\g";
30"GND\g";
31"PVDDCR_CPU0_P1_PVCC\g";
32"GND\g";
33"PVDDCR_CPU0_P1\g";
34"GND\g";
35"PVDDCR_CPU0_P1\g";
36"GND\g";
37"GND\g";
38"P12V_AUX\g";
39"PVDDCR_CPU0_P1\g";
40"PVDDCR_CPU0_P1_LSET1";
41"SW_PVDDCR_CPU0_P1_SW2";
42"PVDDCR_CPU0_P1_IMON1";
43"IND_CPU0_P1_CPL1";
44"IND_CPU0_P1_CPL2";
45"IND_CPU0_P1_CPL1";
46"IND_CPU0_P1_CPL5";
47"NC_PVDDCR_CPU0_P1_GL1_1";
48"NC_PVDDCR_CPU0_P1_GL2_1";
49"NC_PVDDCR_CPU0_P1_DNC1";
50"PVDDCR_CPU0_P1_VCCS";
51"SW_PVDDCR_CPU0_P1_SW1_RC";
52"SW_PVDDCR_CPU0_P1_SW2_RC";
53"PVDDCR_CPU0_P1_VOS2";
54"NC_PVDDCR_CPU0_P1_GL2_2";
55"NC_PVDDCR_CPU0_P1_GL1_2";
56"PVDDCR_CPU0_P1_PWM1";
57"PVDDCR_CPU0_P1_TEMP0";
58"NC_PVDDCR_CPU0_P1_DNC2";
59"PVDDCR_CPU0_P1_LSET2";
60"PVDDCR_CPU0_P1_IMON2";
61"PVDDCR_CPU0_P1_TEMP0";
62"PVDDCR_CPU0_P1_PWM2";
%"UNIVERSAL_GND"
"1","(-7575,1850)","0","pure_quanta_power","I10";
;
CDS_LIB"pure_quanta_power"
HDL_POWER"GND";
"A"1;
%"Q_RES"
"2","(-7575,2600)","0","pure_quanta","I11";
;
LOCATION"PR186"
$SEC"1"
CDS_SEC"1"
VALUE"2.2"
PACK_TYPE"0402LF"
TOLERANCE"1%"
MATERIAL"CHIP"
WATTAGE"1/16W"
CDS_LIB"pure_quanta"
PART_NUMBER"CS-2202FB01";
"A"
$PN"1"28;
"B"
$PN"2"15;
%"UNIVERSAL_GND"
"1","(-7225,2350)","0","pure_quanta_power","I12";
;
CDS_LIB"pure_quanta_power"
HDL_POWER"GND";
"A"2;
%"Q_CAP"
"1","(-7225,2625)","0","pure_quanta","I13";
;
LOCATION"PC259_C0P1_2"
$SEC"1"
CDS_SEC"1"
MATERIAL"X6S"
VALUE"2.2UF"
VOLTAGE"10V"
PACK_TYPE"C0402"
TOLERANCE"10%"
CDS_LIB"pure_quanta"
PART_NUMBER"CH5222KEB01";
"B"
$PN"2"2;
"A"
$PN"1"28;
%"VCC_CORE"
"1","(-7575,3000)","0","pure_quanta_power","I14";
;
HDL_POWER"PVDDCR_CPU0_P1_PVCC"
CDS_LIB"pure_quanta_power";
"A"28;
%"UNIVERSAL_GND"
"1","(-7950,3900)","0","pure_quanta_power","I15";
;
CDS_LIB"pure_quanta_power"
HDL_POWER"GND";
"A"3;
%"Q_CAP"
"1","(-7950,4175)","0","pure_quanta","I16";
;
LOCATION"PC254_1"
$SEC"1"
CDS_SEC"1"
MATERIAL"X7R"
TOLERANCE"10%"
VALUE"0.1UF"
VOLTAGE"25V"
PACK_TYPE"0402"
CDS_LIB"pure_quanta"
PART_NUMBER"CH4104K1B00";
"B"
$PN"2"3;
"A"
$PN"1"50;
%"UNIVERSAL_GND"
"1","(-7625,3975)","0","pure_quanta_power","I17";
;
CDS_LIB"pure_quanta_power"
HDL_POWER"GND";
"A"4;
%"UNIVERSAL_GND"
"1","(-5550,975)","0","pure_quanta_power","I20";
;
CDS_LIB"pure_quanta_power"
HDL_POWER"GND";
"A"29;
%"UNIVERSAL_GND"
"1","(-4650,775)","0","pure_quanta_power","I21";
;
CDS_LIB"pure_quanta_power"
HDL_POWER"GND";
"A"5;
%"Q_RES"
"2","(-4650,1000)","0","pure_quanta","I22";
;
LOCATION"PR486"
$SEC"1"
CDS_SEC"1"
WATTAGE"1/8W"
MATERIAL"EMPTY"
TOLERANCE"1%"
VALUE"1.5"
PACK_TYPE"0402LF"
CDS_LIB"pure_quanta"
PART_NUMBER"CS-1504FB00";
"A"
$PN"1"52;
"B"
$PN"2"5;
%"Q_RES"
"1","(-4250,625)","0","pure_quanta","I23";
;
LOCATION"PR192"
$SEC"1"
CDS_SEC"1"
PACK_TYPE"0402LF"
VALUE"0"
TOLERANCE"5%"
MATERIAL"CHIP"
WATTAGE"1/16W"
CDS_LIB"pure_quanta"
PART_NUMBER"CS00002JB13";
"B"
$PN"2"33;
"A"
$PN"1"53;
%"Q_CAP"
"1","(-4650,1500)","0","pure_quanta","I24";
;
LOCATION"PC173"
$SEC"1"
CDS_SEC"1"
MATERIAL"EMPTY"
TOLERANCE"10%"
VALUE"560PF"
VOLTAGE"50V"
PACK_TYPE"C0402"
CDS_LIB"pure_quanta"
PART_NUMBER"CH1566K1B09";
"B"
$PN"2"52;
"A"
$PN"1"41;
%"Q_CAP"
"1","(-5475,2575)","0","pure_quanta","I25";
;
LOCATION"PC261_2"
$SEC"1"
CDS_SEC"1"
PACK_TYPE"0402"
MATERIAL"X7R"
TOLERANCE"10%"
VALUE"0.1UF"
VOLTAGE"25V"
CDS_LIB"pure_quanta"
PART_NUMBER"CH4104K1B00";
"B"
$PN"2"17;
"A"
$PN"1"16;
%"Q_CAP"
"1","(-5150,2575)","0","pure_quanta","I26";
;
LOCATION"PC263_2"
$SEC"1"
CDS_SEC"1"
MATERIAL"X6S"
TOLERANCE"10%"
VALUE"1UF"
VOLTAGE"25V"
PACK_TYPE"C0402"
CDS_LIB"pure_quanta"
PART_NUMBER"CH5104KEB02";
"B"
$PN"2"17;
"A"
$PN"1"16;
%"UNIVERSAL_GND"
"1","(-5550,3725)","0","pure_quanta_power","I27";
;
CDS_LIB"pure_quanta_power"
HDL_POWER"GND";
"A"30;
%"Q_CAP"
"1","(-4825,2575)","0","pure_quanta","I28";
;
LOCATION"PC265_2"
$SEC"1"
CDS_SEC"1"
TOLERANCE"20%"
MATERIAL"X6S"
PACK_TYPE"C0805"
VALUE"22UF"
VOLTAGE"16V"
CDS_LIB"pure_quanta"
PART_NUMBER"CH6223MEA01";
"B"
$PN"2"17;
"A"
$PN"1"16;
%"Q_CAP"
"1","(-4500,2575)","0","pure_quanta","I29";
;
LOCATION"PC267_2"
$SEC"1"
CDS_SEC"1"
VALUE"22UF"
VOLTAGE"16V"
MATERIAL"X6S"
PACK_TYPE"C0805"
TOLERANCE"20%"
CDS_LIB"pure_quanta"
PART_NUMBER"CH6223MEA01";
"B"
$PN"2"17;
"A"
$PN"1"16;
%"Q_RES"
"1","(-8250,5750)","1","pure_quanta","I3";
;
LOCATION"PR335"
$SEC"1"
CDS_SEC"1"
MATERIAL"CHIP"
TOLERANCE"5%"
PACK_TYPE"0402LF"
VALUE"0"
WATTAGE"1/16W"
CDS_LIB"pure_quanta"
PART_NUMBER"CS00002JB13";
"B"
$PN"2"8;
"A"
$PN"1"31;
%"UNIVERSAL_GND"
"1","(-4200,2225)","0","pure_quanta_power","I30";
;
CDS_LIB"pure_quanta_power"
HDL_POWER"GND";
"A"17;
%"Q_CAP"
"1","(-4200,2575)","0","pure_quanta","I31";
;
LOCATION"PC269_2"
$SEC"1"
CDS_SEC"1"
PACK_TYPE"C0805"
VOLTAGE"16V"
MATERIAL"X6S"
VALUE"22UF"
TOLERANCE"20%"
CDS_LIB"pure_quanta"
PART_NUMBER"CH6223MEA01";
"B"
$PN"2"17;
"A"
$PN"1"16;
%"VCC_CORE"
"1","(-4200,2875)","0","pure_quanta_power","I32";
;
HDL_POWER"SW_P12V_AUX_PVDDCR_CPU0_P1_FLT"
CDS_LIB"pure_quanta_power";
"A"16;
%"UNIVERSAL_GND"
"1","(-4800,3550)","0","pure_quanta_power","I33";
;
CDS_LIB"pure_quanta_power"
HDL_POWER"GND";
"A"6;
%"Q_RES"
"2","(-4800,3775)","0","pure_quanta","I34";
;
LOCATION"PR485"
$SEC"1"
CDS_SEC"1"
MATERIAL"EMPTY"
PACK_TYPE"0402LF"
WATTAGE"1/8W"
TOLERANCE"1%"
VALUE"1.5"
CDS_LIB"pure_quanta"
PART_NUMBER"CS-1504FB00";
"A"
$PN"1"51;
"B"
$PN"2"6;
%"Q_RES"
"1","(-4325,3475)","0","pure_quanta","I35";
;
LOCATION"PR191"
$SEC"1"
CDS_SEC"1"
WATTAGE"1/16W"
VALUE"0"
TOLERANCE"5%"
MATERIAL"CHIP"
PACK_TYPE"0402LF"
CDS_LIB"pure_quanta"
PART_NUMBER"CS00002JB13";
"B"
$PN"2"39;
"A"
$PN"1"20;
%"Q_CAP"
"1","(-7600,4800)","0","pure_quanta","I36";
;
LOCATION"PC256"
$SEC"1"
CDS_SEC"1"
MATERIAL"X6S"
TOLERANCE"10%"
VALUE"2.2UF"
VOLTAGE"10V"
PACK_TYPE"C0402"
CDS_LIB"pure_quanta"
PART_NUMBER"CH5222KEB01";
"B"
$PN"2"7;
"A"
$PN"1"25;
%"Q_RES"
"1","(-7300,4150)","0","pure_quanta","I37";
;
LOCATION"PR187"
$SEC"1"
CDS_SEC"1"
PACK_TYPE"0402LF"
TOLERANCE"1%"
WATTAGE"1/16W"
MATERIAL"EMPTY"
VALUE"8.87K"
CDS_LIB"pure_quanta"
PART_NUMBER"CS28872FB01";
"B"
$PN"2"40;
"A"
$PN"1"4;
%"UNIVERSAL_GND"
"1","(-7600,4600)","0","pure_quanta_power","I39";
;
CDS_LIB"pure_quanta_power"
HDL_POWER"GND";
"A"7;
%"VCC_CORE"
"1","(-8250,5950)","0","pure_quanta_power","I4";
;
HDL_POWER"P5V_AUX"
CDS_LIB"pure_quanta_power";
"A"8;
%"UNIVERSAL_GND"
"1","(-7250,5100)","0","pure_quanta_power","I40";
;
CDS_LIB"pure_quanta_power"
HDL_POWER"GND";
"A"9;
%"Q_RES"
"1","(-7900,5750)","1","pure_quanta","I41";
;
LOCATION"PR336"
$SEC"1"
CDS_SEC"1"
TOLERANCE"5%"
VALUE"0"
PACK_TYPE"0402LF"
MATERIAL"EMPTY"
WATTAGE"1/16W"
CDS_LIB"pure_quanta"
PART_NUMBER"CS00002JB13";
"B"
$PN"2"10;
"A"
$PN"1"31;
%"VCC_CORE"
"1","(-7900,5950)","0","pure_quanta_power","I42";
;
HDL_POWER"P3V3_AUX"
CDS_LIB"pure_quanta_power";
"A"10;
%"Q_RES"
"2","(-7600,5350)","0","pure_quanta","I43";
;
LOCATION"PR185"
$SEC"1"
CDS_SEC"1"
PACK_TYPE"0402LF"
VALUE"2.2"
TOLERANCE"1%"
MATERIAL"CHIP"
WATTAGE"1/16W"
CDS_LIB"pure_quanta"
PART_NUMBER"CS-2202FB01";
"A"
$PN"1"31;
"B"
$PN"2"25;
%"Q_CAP"
"1","(-7250,5375)","0","pure_quanta","I44";
;
LOCATION"PC258_C0P1_1"
$SEC"1"
CDS_SEC"1"
TOLERANCE"10%"
MATERIAL"X6S"
VALUE"2.2UF"
VOLTAGE"10V"
PACK_TYPE"C0402"
CDS_LIB"pure_quanta"
PART_NUMBER"CH5222KEB01";
"B"
$PN"2"9;
"A"
$PN"1"31;
%"VCC_CORE"
"1","(-7425,5950)","0","pure_quanta_power","I45";
;
HDL_POWER"PVDDCR_CPU0_P1_PVCC"
CDS_LIB"pure_quanta_power";
"A"31;
%"Q_CAP"
"1","(-5475,5325)","0","pure_quanta","I46";
;
LOCATION"PC260_1"
$SEC"1"
CDS_SEC"1"
MATERIAL"X7R"
PACK_TYPE"0402"
VALUE"0.1UF"
TOLERANCE"10%"
VOLTAGE"25V"
CDS_LIB"pure_quanta"
PART_NUMBER"CH4104K1B00";
"B"
$PN"2"37;
"A"
$PN"1"23;
%"Q_CAP"
"1","(-5150,5325)","0","pure_quanta","I47";
;
LOCATION"PC262_1"
$SEC"1"
CDS_SEC"1"
VALUE"1UF"
TOLERANCE"10%"
PACK_TYPE"C0402"
VOLTAGE"25V"
MATERIAL"X6S"
CDS_LIB"pure_quanta"
PART_NUMBER"CH5104KEB02";
"B"
$PN"2"37;
"A"
$PN"1"23;
%"Q_CAP"
"1","(-4800,4250)","0","pure_quanta","I48";
;
LOCATION"PC170"
$SEC"1"
CDS_SEC"1"
PACK_TYPE"C0402"
TOLERANCE"10%"
MATERIAL"EMPTY"
VOLTAGE"50V"
VALUE"560PF"
CDS_LIB"pure_quanta"
PART_NUMBER"CH1566K1B09";
"B"
$PN"2"51;
"A"
$PN"1"21;
%"Q_RES"
"1","(-4875,4800)","0","pure_quanta","I49";
;
LOCATION"PR189"
$SEC"1"
CDS_SEC"1"
TOLERANCE"1%"
PACK_TYPE"0402LF"
WATTAGE"1/16W"
MATERIAL"CHIP"
VALUE"5.6"
CDS_LIB"pure_quanta"
PART_NUMBER"CS-5602FB01";
"B"
$PN"2"27;
"A"
$PN"1"24;
%"Q_CAP"
"1","(-7925,1425)","0","pure_quanta","I5";
;
LOCATION"PC255_2"
$SEC"1"
CDS_SEC"1"
MATERIAL"X7R"
TOLERANCE"10%"
VOLTAGE"25V"
PACK_TYPE"0402"
VALUE"0.1UF"
CDS_LIB"pure_quanta"
PART_NUMBER"CH4104K1B00";
"B"
$PN"2"11;
"A"
$PN"1"14;
%"Q_CAP"
"1","(-4825,5325)","0","pure_quanta","I51";
;
LOCATION"PC264_1"
$SEC"1"
CDS_SEC"1"
PACK_TYPE"C0805"
MATERIAL"X6S"
VALUE"22UF"
VOLTAGE"16V"
TOLERANCE"20%"
CDS_LIB"pure_quanta"
PART_NUMBER"CH6223MEA01";
"B"
$PN"2"37;
"A"
$PN"1"23;
%"Q_CAP"
"1","(-4500,5325)","0","pure_quanta","I52";
;
LOCATION"PC266_1"
$SEC"1"
CDS_SEC"1"
PACK_TYPE"C0805"
MATERIAL"X6S"
VALUE"22UF"
VOLTAGE"16V"
TOLERANCE"20%"
CDS_LIB"pure_quanta"
PART_NUMBER"CH6223MEA01";
"B"
$PN"2"37;
"A"
$PN"1"23;
%"Q_CAP"
"1","(-4200,5325)","0","pure_quanta","I53";
;
LOCATION"PC268_1"
$SEC"1"
CDS_SEC"1"
PACK_TYPE"C0805"
VALUE"22UF"
MATERIAL"X6S"
TOLERANCE"20%"
VOLTAGE"16V"
CDS_LIB"pure_quanta"
PART_NUMBER"CH6223MEA01";
"B"
$PN"2"37;
"A"
$PN"1"23;
%"Q_CAP"
"1","(-3675,1925)","0","pure_quanta","I55";
;
LOCATION"PC271"
$SEC"1"
CDS_SEC"1"
VALUE"0.22UF"
PACK_TYPE"0402"
MATERIAL"X7R"
TOLERANCE"10%"
VOLTAGE"16V"
CDS_LIB"pure_quanta"
PART_NUMBER"CH4223K1B00";
"B"
$PN"2"19;
"A"
$PN"1"26;
%"Q_INDUCTOR4P_14"
"1","(-2875,1575)","0","pure_quanta","I56";
;
LOCATION"PL29"
$SEC"1"
CDS_SEC"1"
PART_TYPE"SMLF"
MATERIAL"IND"
VALUE"150NH"
CDS_LIB"pure_quanta"
NEEDS_NO_SIZE"TRUE"
PART_NUMBER"CV+15^0TZ04";
"1"
$PN"1"41;
"4"
$PN"4"33;
"3"
$PN"3"44;
"2"
$PN"2"45;
%"Q_CAPP"
"1","(-2750,2900)","0","pure_quanta","I58";
;
LOCATION"PC275"
$SEC"1"
CDS_SEC"1"
VALUE"220UF"
VOLTAGE"4V"
MATERIAL"SPCAP"
PACK_TYPE"SMLF"
TOLERANCE"20%"
CDS_LIB"pure_quanta"
PART_NUMBER"CH122KM8801";
"A"
$PN"1"35;
"B"
$PN"2"34;
%"Q_CAPP"
"1","(-2425,2900)","0","pure_quanta","I59";
;
LOCATION"PC276"
$SEC"1"
CDS_SEC"1"
VALUE"220UF"
TOLERANCE"20%"
VOLTAGE"4V"
PACK_TYPE"SMLF"
MATERIAL"SPCAP"
CDS_LIB"pure_quanta"
PART_NUMBER"CH122KM8801";
"A"
$PN"1"35;
"B"
$PN"2"34;
%"Q_CAPP"
"1","(-2100,2900)","0","pure_quanta","I60";
;
LOCATION"PC277"
$SEC"1"
CDS_SEC"1"
VOLTAGE"4V"
MATERIAL"SPCAP"
PACK_TYPE"SMLF"
VALUE"220UF"
TOLERANCE"20%"
CDS_LIB"pure_quanta"
PART_NUMBER"CH122KM8801";
"A"
$PN"1"35;
"B"
$PN"2"34;
%"Q_CAP"
"1","(-1700,1525)","0","pure_quanta","I61";
;
LOCATION"PC280_2"
$SEC"1"
CDS_SEC"1"
VOLTAGE"4V"
VALUE"22UF"
TOLERANCE"20%"
MATERIAL"X6S"
PACK_TYPE"C0805"
CDS_LIB"pure_quanta"
PART_NUMBER"CH622KMEA03";
"B"
$PN"2"32;
"A"
$PN"1"33;
%"UNIVERSAL_GND"
"1","(-1275,1175)","0","pure_quanta_power","I62";
;
CDS_LIB"pure_quanta_power"
HDL_POWER"GND";
"A"32;
%"Q_CAP"
"1","(-1275,1525)","0","pure_quanta","I63";
;
LOCATION"PC282_2"
$SEC"1"
CDS_SEC"1"
VOLTAGE"4V"
VALUE"22UF"
TOLERANCE"20%"
MATERIAL"X6S"
PACK_TYPE"C0805"
CDS_LIB"pure_quanta"
PART_NUMBER"CH622KMEA03";
"B"
$PN"2"32;
"A"
$PN"1"33;
%"VCC_CORE"
"1","(-1275,1850)","0","pure_quanta_power","I64";
;
HDL_POWER"PVDDCR_CPU0_P1"
CDS_LIB"pure_quanta_power";
"A"33;
%"UNIVERSAL_GND"
"1","(-1800,2525)","0","pure_quanta_power","I65";
;
CDS_LIB"pure_quanta_power"
HDL_POWER"GND";
"A"34;
%"Q_CAPP"
"1","(-1800,2900)","0","pure_quanta","I66";
;
LOCATION"PC279"
$SEC"1"
CDS_SEC"1"
VALUE"220UF"
TOLERANCE"20%"
VOLTAGE"4V"
PACK_TYPE"SMLF"
MATERIAL"SPCAP"
CDS_LIB"pure_quanta"
PART_NUMBER"CH122KM8801";
"A"
$PN"1"35;
"B"
$PN"2"34;
%"VCC_CORE"
"1","(-1800,3200)","0","pure_quanta_power","I67";
;
HDL_POWER"PVDDCR_CPU0_P1"
CDS_LIB"pure_quanta_power";
"A"35;
%"UNIVERSAL_GND"
"1","(-925,3925)","0","pure_quanta_power","I68";
;
CDS_LIB"pure_quanta_power"
HDL_POWER"GND";
"A"36;
%"UNIVERSAL_GND"
"1","(-4000,4975)","0","pure_quanta_power","I69";
;
CDS_LIB"pure_quanta_power"
HDL_POWER"GND";
"A"37;
%"Q_CAPP"
"1","(-3850,5325)","0","pure_quanta","I70";
;
LOCATION"PC272"
$SEC"1"
CDS_SEC"1"
MATERIAL"OSCON"
VOLTAGE"16V"
PACK_TYPE"THLF"
TOLERANCE"20%"
VALUE"270UF"
CDS_LIB"pure_quanta"
PART_NUMBER"CC72703MD38";
"A"
$PN"1"23;
"B"
$PN"2"37;
%"Q_CAPP"
"1","(-3475,5325)","0","pure_quanta","I71";
;
LOCATION"PC273"
$SEC"1"
CDS_SEC"1"
VALUE"270UF"
TOLERANCE"20%"
PACK_TYPE"THLF"
VOLTAGE"16V"
MATERIAL"OSCON"
CDS_LIB"pure_quanta"
PART_NUMBER"CC72703MD38";
"A"
$PN"1"23;
"B"
$PN"2"37;
%"Q_INDUCTOR"
"1","(-2900,5525)","0","pure_quanta","I73";
;
LOCATION"PL30"
$SEC"1"
CDS_SEC"1"
VALUE"50NH/86A"
MATERIAL"IND"
PACK_TYPE"SMLF"
CDS_LIB"pure_quanta"
NEEDS_NO_SIZE"TRUE"
PART_NUMBER"CVA50^0MZ09";
"1"
$PN"1"23;
"2"
$PN"2"38;
%"Q_CAP"
"1","(-2550,5350)","0","pure_quanta","I74";
;
LOCATION"PC6004"
$SEC"1"
CDS_SEC"1"
PACK_TYPE"0402"
VOLTAGE"25V"
VALUE"0.1UF"
MATERIAL"X7R"
TOLERANCE"10%"
CDS_LIB"pure_quanta"
PART_NUMBER"CH4104K1B00";
"B"
$PN"2"13;
"A"
$PN"1"38;
%"VCC_CORE"
"1","(-2550,5675)","0","pure_quanta_power","I75";
;
HDL_POWER"P12V_AUX"
CDS_LIB"pure_quanta_power";
"A"38;
%"Q_CAP"
"1","(-1650,4275)","0","pure_quanta","I76";
;
LOCATION"PC281_1"
$SEC"1"
CDS_SEC"1"
VOLTAGE"4V"
VALUE"22UF"
MATERIAL"X6S"
PACK_TYPE"C0805"
TOLERANCE"20%"
CDS_LIB"pure_quanta"
PART_NUMBER"CH622KMEA03";
"B"
$PN"2"36;
"A"
$PN"1"39;
%"Q_CAP"
"1","(-1225,4275)","0","pure_quanta","I77";
;
LOCATION"PC283_1"
$SEC"1"
CDS_SEC"1"
TOLERANCE"20%"
MATERIAL"X6S"
VALUE"22UF"
VOLTAGE"4V"
PACK_TYPE"C0805"
CDS_LIB"pure_quanta"
PART_NUMBER"CH622KMEA03";
"B"
$PN"2"36;
"A"
$PN"1"39;
%"Q_RES"
"2","(-925,4275)","0","pure_quanta","I78";
;
LOCATION"PR337"
$SEC"1"
CDS_SEC"1"
PACK_TYPE"0402LF"
VALUE"1K"
TOLERANCE"1%"
MATERIAL"CHIP"
WATTAGE"1/16W"
CDS_LIB"pure_quanta"
PART_NUMBER"CS21002FB06";
"A"
$PN"1"39;
"B"
$PN"2"36;
%"VCC_CORE"
"1","(-925,4600)","0","pure_quanta_power","I79";
;
HDL_POWER"PVDDCR_CPU0_P1"
CDS_LIB"pure_quanta_power";
"A"39;
%"Q_RES"
"1","(-7275,1400)","0","pure_quanta","I80";
;
LOCATION"PR188"
$SEC"1"
CDS_SEC"1"
WATTAGE"1/16W"
MATERIAL"EMPTY"
TOLERANCE"1%"
VALUE"8.87K"
PACK_TYPE"0402LF"
CDS_LIB"pure_quanta"
PART_NUMBER"CS28872FB01";
"B"
$PN"2"59;
"A"
$PN"1"12;
%"UNIVERSAL_GND"
"1","(-7925,1150)","0","pure_quanta_power","I81";
;
CDS_LIB"pure_quanta_power"
HDL_POWER"GND";
"A"11;
%"UNIVERSAL_GND"
"1","(-7600,1225)","0","pure_quanta_power","I82";
;
CDS_LIB"pure_quanta_power"
HDL_POWER"GND";
"A"12;
%"Q_RES"
"1","(-4675,2050)","0","pure_quanta","I83";
;
LOCATION"PR190"
$SEC"1"
CDS_SEC"1"
WATTAGE"1/16W"
TOLERANCE"1%"
PACK_TYPE"0402LF"
VALUE"5.6"
MATERIAL"CHIP"
CDS_LIB"pure_quanta"
PART_NUMBER"CS-5602FB01";
"B"
$PN"2"26;
"A"
$PN"1"18;
%"Q_CAPP"
"1","(-3100,2900)","0","pure_quanta","I84";
;
LOCATION"PC105"
$SEC"1"
CDS_SEC"1"
VOLTAGE"4V"
TOLERANCE"20%"
VALUE"220UF"
MATERIAL"SPCAP"
PACK_TYPE"SMLF"
CDS_LIB"pure_quanta"
PART_NUMBER"CH122KM8801";
"A"
$PN"1"35;
"B"
$PN"2"34;
%"Q_CAP"
"1","(-2025,4275)","0","pure_quanta","I85";
;
LOCATION"PC278"
$SEC"1"
CDS_SEC"1"
MATERIAL"X7R"
TOLERANCE"10%"
VALUE"0.1UF"
VOLTAGE"25V"
PACK_TYPE"0402"
CDS_LIB"pure_quanta"
PART_NUMBER"CH4104K1B00";
"B"
$PN"2"36;
"A"
$PN"1"39;
%"UNIVERSAL_GND"
"1","(-2550,5050)","0","pure_quanta_power","I86";
;
CDS_LIB"pure_quanta_power"
HDL_POWER"GND";
"A"13;
%"VCC_CORE"
"1","(-4025,5650)","0","pure_quanta_power","I87";
;
HDL_POWER"SW_P12V_AUX_PVDDCR_CPU0_P1_FLT"
CDS_LIB"pure_quanta_power";
"A"23;
%"ISL99390FRZTR5935"
"1","(-6125,4450)","0","pure_quanta","I88";
;
LOCATION"PU4"
$SEC"1"
CDS_SEC"1"
MATERIAL"IC"
VALUE"ISL99390FRZ-TR5935"
PART_TYPE"SMLF"
NEEDS_NO_SIZE"TRUE"
CDS_LMAN_SYM_OUTLINE"-300,700,250,-650"
CDS_LIB"pure_quanta"
PART_NUMBER"AL099390004";
"PGND2"
$PN"7_9-20_24"30;
"GL2"
$PN"41"48;
"GL1"
$PN"6"47;
"DNC"
$PN"31"49;
"EN"
$PN"35"25;
"PGND3"
$PN"40"30;
"VOS"
$PN"1"20;
"VIN2"
$PN"30"23;
"PGND1"
$PN"5"30;
"SW"
$PN"10_19"21;
"LSET"
$PN"37"40;
"IOUT"
$PN"38"42;
"TOUT_FLT"
$PN"36"57;
"PVCC"
$PN"4"31;
"PHASE"
$PN"32"22;
"VIN1"
$PN"25_29"23;
"BOOT"
$PN"33"24;
"AGND"
$PN"2"30;
"VCC"
$PN"3"25;
"REFIN"
$PN"39"50;
"PWM"
$PN"34"56;
%"Q_CAP"
"1","(-4050,4675)","0","pure_quanta","I89";
;
LOCATION"PC270"
$SEC"1"
CDS_SEC"1"
VALUE"0.22UF"
VOLTAGE"16V"
TOLERANCE"10%"
MATERIAL"X7R"
PACK_TYPE"0402"
CDS_LIB"pure_quanta"
PART_NUMBER"CH4223K1B00";
"B"
$PN"2"22;
"A"
$PN"1"27;
%"Q_CAP"
"1","(-7575,2050)","0","pure_quanta","I9";
;
LOCATION"PC257"
$SEC"1"
CDS_SEC"1"
MATERIAL"X6S"
TOLERANCE"10%"
VALUE"2.2UF"
VOLTAGE"10V"
PACK_TYPE"C0402"
CDS_LIB"pure_quanta"
PART_NUMBER"CH5222KEB01";
"B"
$PN"2"1;
"A"
$PN"1"15;
%"Q_INDUCTOR4P_14"
"1","(-3325,4325)","0","pure_quanta","I90";
;
LOCATION"PL28"
$SEC"1"
CDS_SEC"1"
PART_TYPE"SMLF"
VALUE"150NH"
MATERIAL"IND"
CDS_LIB"pure_quanta"
NEEDS_NO_SIZE"TRUE"
PART_NUMBER"CV+15^0TZ04";
"1"
$PN"1"21;
"4"
$PN"4"39;
"3"
$PN"3"43;
"2"
$PN"2"46;
%"ISL99390FRZTR5935"
"1","(-6100,1700)","0","pure_quanta","I91";
;
LOCATION"PU26"
$SEC"1"
CDS_SEC"1"
PART_TYPE"SMLF"
MATERIAL"IC"
VALUE"ISL99390FRZ-TR5935"
CDS_LIB"pure_quanta"
CDS_LMAN_SYM_OUTLINE"-300,700,250,-650"
NEEDS_NO_SIZE"TRUE"
PART_NUMBER"AL099390004";
"PGND2"
$PN"7_9-20_24"29;
"GL2"
$PN"41"54;
"GL1"
$PN"6"55;
"DNC"
$PN"31"58;
"EN"
$PN"35"15;
"PGND3"
$PN"40"29;
"VOS"
$PN"1"53;
"VIN2"
$PN"30"16;
"PGND1"
$PN"5"29;
"SW"
$PN"10_19"41;
"LSET"
$PN"37"59;
"IOUT"
$PN"38"60;
"TOUT_FLT"
$PN"36"61;
"PVCC"
$PN"4"28;
"PHASE"
$PN"32"19;
"VIN1"
$PN"25_29"16;
"BOOT"
$PN"33"18;
"AGND"
$PN"2"29;
"VCC"
$PN"3"15;
"REFIN"
$PN"39"14;
"PWM"
$PN"34"62;
END.
